# S9S_MB_2U (Grand Teton) — schematic netlist excerpt (pin names and nets, part order shuffled) for the footprints in the layout excerpt that follows; sources: Cadence DE-HDL packaged netlist, KiCad conversion of 03242023_DA0F0TMBIJ0_F0T_Motherboard_J_brd_V01_OCP.brd

R753  Q_RES  10 1% CHIP  pkg 0402LF  page 132 : A = JTAG_DBP_TDI ; B = JTAG_DBP_TDI_PCH
R750  Q_RES  150 1% CHIP  pkg 0402LF  page 132 : A = P1V05_PCH_AUX ; B = H_DBP_PREQ_N_PCH

(kicad_pcb
	(version 20260206)
	(generator "pcbnew")
	(generator_version "10.0")
	(general
		(thickness 1.6)
		(legacy_teardrops no)
	)
	(paper "A4")
	(title_block
		(title "03242023_DA0F0TMBIJ0_F0T_Motherboard_J_brd_V01_OCP.brd")
		(comment 1 "Grand Teton / footprints 2353-2354 of 6105")
	)
	(layers
		(0 "F.Cu" signal "TOP")
		(4 "In1.Cu" signal "GND")
		(6 "In2.Cu" signal "IN1")
		(8 "In3.Cu" signal "GND1")
		(10 "In4.Cu" signal "IN2")
		(12 "In5.Cu" signal "GND2")
		(14 "In6.Cu" signal "IN3")
		(16 "In7.Cu" signal "GND3")
		(18 "In8.Cu" signal "VCC")
		(20 "In9.Cu" signal "VCC1")
		(22 "In10.Cu" signal "GND4")
		(24 "In11.Cu" signal "IN4")
		(26 "In12.Cu" signal "GND5")
		(28 "In13.Cu" signal "IN5")
		(30 "In14.Cu" signal "GND6")
		(32 "In15.Cu" signal "IN6")
		(34 "In16.Cu" signal "GND7")
		(2 "B.Cu" signal "BOTTOM")
		(9 "F.Adhes" user "F.Adhesive")
		(11 "B.Adhes" user "B.Adhesive")
		(13 "F.Paste" user "Package Geometry/Pastemask Top")
		(15 "B.Paste" user "Package Geometry/Pastemask Bottom")
		(5 "F.SilkS" user "Ref Des/Silkscreen Top")
		(7 "B.SilkS" user "Ref Des/Silkscreen Bottom")
		(1 "F.Mask" user "Board Geometry/Soldermask Top")
		(3 "B.Mask" user "Board Geometry/Soldermask Bottom")
		(17 "Dwgs.User" user "User.Drawings")
		(19 "Cmts.User" user "User.Comments")
		(21 "Eco1.User" user "User.Eco1")
		(23 "Eco2.User" user "User.Eco2")
		(25 "Edge.Cuts" user "Board Geometry/Outline")
		(27 "Margin" user)
		(31 "F.CrtYd" user "Package Geometry/Place Bound Top")
		(29 "B.CrtYd" user "Package Geometry/Place Bound Bottom")
		(35 "F.Fab" user "Ref Des/Assembly Top")
		(33 "B.Fab" user "Ref Des/Assembly Bottom")
	)
	(footprint ""
		(layer "F.Cu")
		(at 371.602 -39.969948 90)
		(property "Reference" "R750"
			(at 0 0 90)
			(layer "F.SilkS")
			(hide yes)
			(effects
				(font
					(size 1.27 1.27)
				)
			)
		)
		(property "Value" ""
			(at 0 0 90)
			(layer "F.Fab")
			(effects
				(font
					(size 1.27 1.27)
				)
			)
		)
		(duplicate_pad_numbers_are_jumpers no)
		(fp_line
			(start 0.7874 -0.4064)
			(end 0.7874 0.4064)
			(stroke
				(width 0.1524)
				(type default)
			)
			(layer "F.SilkS")
		)
		(fp_line
			(start -0.7874 -0.4064)
			(end 0.7874 -0.4064)
			(stroke
				(width 0.1524)
				(type default)
			)
			(layer "F.SilkS")
		)
		(fp_line
			(start 0.7874 0.4064)
			(end -0.7874 0.4064)
			(stroke
				(width 0.1524)
				(type default)
			)
			(layer "F.SilkS")
		)
		(fp_line
			(start -0.7874 0.4064)
			(end -0.7874 -0.4064)
			(stroke
				(width 0.1524)
				(type default)
			)
			(layer "F.SilkS")
		)
		(fp_line
			(start -0.12065 -0.305054)
			(end -0.12065 -0.2794)
			(stroke
				(width 0.1)
				(type default)
			)
			(layer "F.Fab")
		)
		(fp_line
			(start -0.67945 -0.305054)
			(end -0.12065 -0.305054)
			(stroke
				(width 0.1)
				(type default)
			)
			(layer "F.Fab")
		)
		(fp_line
			(start 0.67945 -0.3048)
			(end 0.67945 0.3048)
			(stroke
				(width 0.1)
				(type default)
			)
			(layer "F.Fab")
		)
		(fp_line
			(start 0.12065 -0.3048)
			(end 0.67945 -0.3048)
			(stroke
				(width 0.1)
				(type default)
			)
			(layer "F.Fab")
		)
		(fp_line
			(start 0.12065 -0.2794)
			(end 0.12065 -0.3048)
			(stroke
				(width 0.1)
				(type default)
			)
			(layer "F.Fab")
		)
		(fp_line
			(start -0.12065 -0.2794)
			(end 0.12065 -0.2794)
			(stroke
				(width 0.1)
				(type default)
			)
			(layer "F.Fab")
		)
		(fp_line
			(start 0.120396 0.2794)
			(end -0.12065 0.2794)
			(stroke
				(width 0.1)
				(type default)
			)
			(layer "F.Fab")
		)
		(fp_line
			(start -0.12065 0.2794)
			(end -0.12065 0.3048)
			(stroke
				(width 0.1)
				(type default)
			)
			(layer "F.Fab")
		)
		(fp_line
			(start 0.67945 0.3048)
			(end 0.120396 0.3048)
			(stroke
				(width 0.1)
				(type default)
			)
			(layer "F.Fab")
		)
		(fp_line
			(start 0.120396 0.3048)
			(end 0.120396 0.2794)
			(stroke
				(width 0.1)
				(type default)
			)
			(layer "F.Fab")
		)
		(fp_line
			(start -0.12065 0.3048)
			(end -0.67945 0.3048)
			(stroke
				(width 0.1)
				(type default)
			)
			(layer "F.Fab")
		)
		(fp_line
			(start -0.67945 0.3048)
			(end -0.67945 -0.305054)
			(stroke
				(width 0.1)
				(type default)
			)
			(layer "F.Fab")
		)
		(pad "1" smd circle
			(at -0.40005 0 90)
			(size 0 0)
			(layers "F.Cu" "F.Mask" "F.Paste")
			(net "P1V05_PCH_AUX")
		)
		(pad "2" smd circle
			(at 0.40005 0 90)
			(size 0 0)
			(layers "F.Cu" "F.Mask" "F.Paste")
			(net "H_DBP_PREQ_N_PCH")
		)
	)
	(footprint ""
		(layer "F.Cu")
		(at 361.412282 -57.898792 180)
		(property "Reference" "R753"
			(at 0 0 180)
			(layer "F.SilkS")
			(hide yes)
			(effects
				(font
					(size 1.27 1.27)
				)
			)
		)
		(property "Value" ""
			(at 0 0 180)
			(layer "F.Fab")
			(effects
				(font
					(size 1.27 1.27)
				)
			)
		)
		(duplicate_pad_numbers_are_jumpers no)
		(fp_line
			(start 0.7874 0.4064)
			(end -0.7874 0.4064)
			(stroke
				(width 0.1524)
				(type default)
			)
			(layer "F.SilkS")
		)
		(fp_line
			(start 0.7874 -0.4064)
			(end 0.7874 0.4064)
			(stroke
				(width 0.1524)
				(type default)
			)
			(layer "F.SilkS")
		)
		(fp_line
			(start -0.7874 0.4064)
			(end -0.7874 -0.4064)
			(stroke
				(width 0.1524)
				(type default)
			)
			(layer "F.SilkS")
		)
		(fp_line
			(start -0.7874 -0.4064)
			(end 0.7874 -0.4064)
			(stroke
				(width 0.1524)
				(type default)
			)
			(layer "F.SilkS")
		)
		(fp_line
			(start 0.67945 0.3048)
			(end 0.120396 0.3048)
			(stroke
				(width 0.1)
				(type default)
			)
			(layer "F.Fab")
		)
		(fp_line
			(start 0.67945 -0.3048)
			(end 0.67945 0.3048)
			(stroke
				(width 0.1)
				(type default)
			)
			(layer "F.Fab")
		)
		(fp_line
			(start 0.12065 -0.2794)
			(end 0.12065 -0.3048)
			(stroke
				(width 0.1)
				(type default)
			)
			(layer "F.Fab")
		)
		(fp_line
			(start 0.12065 -0.3048)
			(end 0.67945 -0.3048)
			(stroke
				(width 0.1)
				(type default)
			)
			(layer "F.Fab")
		)
		(fp_line
			(start 0.120396 0.3048)
			(end 0.120396 0.2794)
			(stroke
				(width 0.1)
				(type default)
			)
			(layer "F.Fab")
		)
		(fp_line
			(start 0.120396 0.2794)
			(end -0.12065 0.2794)
			(stroke
				(width 0.1)
				(type default)
			)
			(layer "F.Fab")
		)
		(fp_line
			(start -0.12065 0.3048)
			(end -0.67945 0.3048)
			(stroke
				(width 0.1)
				(type default)
			)
			(layer "F.Fab")
		)
		(fp_line
			(start -0.12065 0.2794)
			(end -0.12065 0.3048)
			(stroke
				(width 0.1)
				(type default)
			)
			(layer "F.Fab")
		)
		(fp_line
			(start -0.12065 -0.2794)
			(end 0.12065 -0.2794)
			(stroke
				(width 0.1)
				(type default)
			)
			(layer "F.Fab")
		)
		(fp_line
			(start -0.12065 -0.305054)
			(end -0.12065 -0.2794)
			(stroke
				(width 0.1)
				(type default)
			)
			(layer "F.Fab")
		)
		(fp_line
			(start -0.67945 0.3048)
			(end -0.67945 -0.305054)
			(stroke
				(width 0.1)
				(type default)
			)
			(layer "F.Fab")
		)
		(fp_line
			(start -0.67945 -0.305054)
			(end -0.12065 -0.305054)
			(stroke
				(width 0.1)
				(type default)
			)
			(layer "F.Fab")
		)
		(pad "1" smd circle
			(at -0.40005 0 180)
			(size 0 0)
			(layers "F.Cu" "F.Mask" "F.Paste")
			(net "JTAG_DBP_TDI")
		)
		(pad "2" smd circle
			(at 0.40005 0 180)
			(size 0 0)
			(layers "F.Cu" "F.Mask" "F.Paste")
			(net "JTAG_DBP_TDI_PCH")
		)
	)
)
